(kicad_pcb
	(version 20260206)
	(generator "pcbnew")
	(generator_version "10.0")
	(general
		(thickness 1.6)
		(legacy_teardrops no)
	)
	(paper "A4")
	(title_block
		(title "v2-pdb — ms_pdb_v2.brd")
		(comment 1 "Open CloudServer (Microsoft) / footprints 118-127 of 348")
	)
	(layers
		(0 "F.Cu" signal "TOP")
		(4 "In1.Cu" signal "GND")
		(6 "In2.Cu" signal "IN1")
		(8 "In3.Cu" signal "VCC")
		(10 "In4.Cu" signal "VCC1")
		(12 "In5.Cu" signal "IN2")
		(14 "In6.Cu" signal "GND1")
		(2 "B.Cu" signal "BOTTOM")
		(9 "F.Adhes" user "F.Adhesive")
		(11 "B.Adhes" user "B.Adhesive")
		(13 "F.Paste" user "Package Geometry/Pastemask Top")
		(15 "B.Paste" user "Package Geometry/Pastemask Bottom")
		(5 "F.SilkS" user "Ref Des/Silkscreen Top")
		(7 "B.SilkS" user "Ref Des/Silkscreen Bottom")
		(1 "F.Mask" user "Board Geometry/Soldermask Top")
		(3 "B.Mask" user "Board Geometry/Soldermask Bottom")
		(17 "Dwgs.User" user "User.Drawings")
		(19 "Cmts.User" user "User.Comments")
		(21 "Eco1.User" user "User.Eco1")
		(23 "Eco2.User" user "User.Eco2")
		(25 "Edge.Cuts" user "Board Geometry/Outline")
		(27 "Margin" user)
		(31 "F.CrtYd" user "Package Geometry/Place Bound Top")
		(29 "B.CrtYd" user "Package Geometry/Place Bound Bottom")
		(35 "F.Fab" user "Ref Des/Assembly Top")
		(33 "B.Fab" user "Ref Des/Assembly Bottom")
	)
	(footprint ""
		(layer "F.Cu")
		(at 26.102056 -271.14881)
		(property "Reference" "R77"
			(at -4.037838 -0.005334 0)
			(unlocked yes)
			(layer "F.SilkS")
			(effects
				(font
					(size 0.7874 0.5842)
					(thickness 0.1524)
				)
				(justify left)
			)
		)
		(property "Value" ""
			(at 0 0 0)
			(layer "F.Fab")
			(effects
				(font
					(size 1.27 1.27)
				)
			)
		)
		(duplicate_pad_numbers_are_jumpers no)
		(fp_line
			(start -0.7874 -0.4064)
			(end 0.7874 -0.4064)
			(stroke
				(width 0.1524)
				(type default)
			)
			(layer "F.SilkS")
		)
		(fp_line
			(start -0.7874 0.4064)
			(end -0.7874 -0.4064)
			(stroke
				(width 0.1524)
				(type default)
			)
			(layer "F.SilkS")
		)
		(fp_line
			(start 0.7874 -0.4064)
			(end 0.7874 0.4064)
			(stroke
				(width 0.1524)
				(type default)
			)
			(layer "F.SilkS")
		)
		(fp_line
			(start 0.7874 0.4064)
			(end -0.7874 0.4064)
			(stroke
				(width 0.1524)
				(type default)
			)
			(layer "F.SilkS")
		)
		(fp_poly
			(pts
				(xy -0.508 0.2794) (xy -0.508 0.2286) (xy -0.635 0.2286) (xy -0.635 -0.254) (xy -0.5334 -0.254)
				(xy -0.5334 -0.2794) (xy 0.5334 -0.2794) (xy 0.5334 -0.254) (xy 0.635 -0.254) (xy 0.635 0.254) (xy 0.5334 0.254)
				(xy 0.5334 0.2794)
			)
			(stroke
				(width 0)
				(type default)
			)
			(fill no)
			(layer "F.CrtYd")
		)
		(pad "1" smd rect
			(at 0.40005 0)
			(size 0.4572 0.508)
			(layers "F.Cu" "F.Mask" "F.Paste")
			(net "PSU4_RESET")
		)
		(pad "2" smd rect
			(at -0.40005 0)
			(size 0.4572 0.508)
			(layers "F.Cu" "F.Mask" "F.Paste")
			(net "GND")
		)
	)
	(footprint ""
		(layer "F.Cu")
		(at 68.639436 -374.919748 -90)
		(property "Reference" "C57"
			(at -3.246628 0.156972 90)
			(unlocked yes)
			(layer "F.SilkS")
			(effects
				(font
					(size 0.7874 0.5842)
					(thickness 0.1524)
				)
			)
		)
		(property "Value" ""
			(at 0 0 270)
			(layer "F.Fab")
			(effects
				(font
					(size 1.27 1.27)
				)
			)
		)
		(duplicate_pad_numbers_are_jumpers no)
		(fp_line
			(start -1.2954 0.5842)
			(end -1.2954 -0.5842)
			(stroke
				(width 0.1524)
				(type default)
			)
			(layer "F.SilkS")
		)
		(fp_line
			(start 1.2954 0.5842)
			(end -1.2954 0.5842)
			(stroke
				(width 0.1524)
				(type default)
			)
			(layer "F.SilkS")
		)
		(fp_line
			(start -1.2954 -0.5842)
			(end 1.2954 -0.5842)
			(stroke
				(width 0.1524)
				(type default)
			)
			(layer "F.SilkS")
		)
		(fp_line
			(start 0 -0.5842)
			(end 0 0.5842)
			(stroke
				(width 0.1524)
				(type default)
			)
			(layer "F.SilkS")
		)
		(fp_line
			(start 1.2954 -0.5842)
			(end 1.2954 0.5842)
			(stroke
				(width 0.1524)
				(type default)
			)
			(layer "F.SilkS")
		)
		(fp_poly
			(pts
				(xy 0.8636 -0.4572) (xy 0.8636 -0.3556) (xy 1.143 -0.3556) (xy 1.143 0.3556) (xy 0.8636 0.3556)
				(xy 0.8636 0.4572) (xy -0.8636 0.4572) (xy -0.8636 0.3556) (xy -1.143 0.3556) (xy -1.143 -0.3556)
				(xy -0.8636 -0.3556) (xy -0.8636 -0.4572)
			)
			(stroke
				(width 0)
				(type default)
			)
			(fill no)
			(layer "F.CrtYd")
		)
		(fp_line
			(start -0.884936 0.504952)
			(end -0.884936 -0.504952)
			(stroke
				(width 0.1)
				(type default)
			)
			(layer "F.Fab")
		)
		(fp_line
			(start 0.884936 0.504952)
			(end -0.884936 0.504952)
			(stroke
				(width 0.1)
				(type default)
			)
			(layer "F.Fab")
		)
		(fp_line
			(start -0.884936 -0.504952)
			(end 0.884936 -0.504952)
			(stroke
				(width 0.1)
				(type default)
			)
			(layer "F.Fab")
		)
		(fp_line
			(start 0.884936 -0.504952)
			(end 0.884936 0.504952)
			(stroke
				(width 0.1)
				(type default)
			)
			(layer "F.Fab")
		)
		(pad "1" smd rect
			(at 0.7366 0)
			(size 0.7112 0.8128)
			(layers "F.Cu" "F.Mask" "F.Paste")
			(net "P12V")
		)
		(pad "2" smd rect
			(at -0.7366 0)
			(size 0.7112 0.8128)
			(layers "F.Cu" "F.Mask" "F.Paste")
			(net "GND")
		)
	)
	(footprint ""
		(layer "F.Cu")
		(at 68.310252 -127.633476 90)
		(property "Reference" "C27"
			(at 1.193546 -0.121412 90)
			(unlocked yes)
			(layer "F.SilkS")
			(effects
				(font
					(size 0.7874 0.5842)
					(thickness 0.1524)
				)
				(justify left)
			)
		)
		(property "Value" ""
			(at 0 0 90)
			(layer "F.Fab")
			(effects
				(font
					(size 1.27 1.27)
				)
			)
		)
		(duplicate_pad_numbers_are_jumpers no)
		(fp_line
			(start 0.7874 -0.4064)
			(end 0.7874 0.4064)
			(stroke
				(width 0.1524)
				(type default)
			)
			(layer "F.SilkS")
		)
		(fp_line
			(start -0.7874 -0.4064)
			(end 0.7874 -0.4064)
			(stroke
				(width 0.1524)
				(type default)
			)
			(layer "F.SilkS")
		)
		(fp_line
			(start 0 0.381)
			(end 0 -0.381)
			(stroke
				(width 0.1524)
				(type default)
			)
			(layer "F.SilkS")
		)
		(fp_line
			(start 0.7874 0.4064)
			(end -0.7874 0.4064)
			(stroke
				(width 0.1524)
				(type default)
			)
			(layer "F.SilkS")
		)
		(fp_line
			(start -0.7874 0.4064)
			(end -0.7874 -0.4064)
			(stroke
				(width 0.1524)
				(type default)
			)
			(layer "F.SilkS")
		)
		(fp_poly
			(pts
				(xy -0.5334 0.254) (xy -0.635 0.254) (xy -0.635 0.2286) (xy -0.635 -0.254) (xy -0.5334 -0.254) (xy -0.5334 -0.2794)
				(xy 0.5334 -0.2794) (xy 0.5334 -0.254) (xy 0.635 -0.254) (xy 0.635 0.254) (xy 0.5334 0.254) (xy 0.5334 0.2794)
				(xy -0.508 0.2794) (xy -0.5334 0.2794)
			)
			(stroke
				(width 0)
				(type default)
			)
			(fill no)
			(layer "F.CrtYd")
		)
		(pad "1" smd rect
			(at 0.40005 0 90)
			(size 0.4572 0.508)
			(layers "F.Cu" "F.Mask" "F.Paste")
			(net "P12V")
		)
		(pad "2" smd rect
			(at -0.40005 0 90)
			(size 0.4572 0.508)
			(layers "F.Cu" "F.Mask" "F.Paste")
			(net "GND")
		)
	)
	(footprint ""
		(layer "F.Cu")
		(at 73.927716 -393.452604 90)
		(property "Reference" "C70"
			(at 1.084834 -0.053848 90)
			(unlocked yes)
			(layer "F.SilkS")
			(effects
				(font
					(size 0.7874 0.5842)
					(thickness 0.1524)
				)
				(justify left)
			)
		)
		(property "Value" ""
			(at 0 0 90)
			(layer "F.Fab")
			(effects
				(font
					(size 1.27 1.27)
				)
			)
		)
		(duplicate_pad_numbers_are_jumpers no)
		(fp_line
			(start 0.7874 -0.4064)
			(end 0.7874 0.4064)
			(stroke
				(width 0.1524)
				(type default)
			)
			(layer "F.SilkS")
		)
		(fp_line
			(start -0.7874 -0.4064)
			(end 0.7874 -0.4064)
			(stroke
				(width 0.1524)
				(type default)
			)
			(layer "F.SilkS")
		)
		(fp_line
			(start 0 0.381)
			(end 0 -0.381)
			(stroke
				(width 0.1524)
				(type default)
			)
			(layer "F.SilkS")
		)
		(fp_line
			(start 0.7874 0.4064)
			(end -0.7874 0.4064)
			(stroke
				(width 0.1524)
				(type default)
			)
			(layer "F.SilkS")
		)
		(fp_line
			(start -0.7874 0.4064)
			(end -0.7874 -0.4064)
			(stroke
				(width 0.1524)
				(type default)
			)
			(layer "F.SilkS")
		)
		(fp_poly
			(pts
				(xy -0.5334 0.254) (xy -0.635 0.254) (xy -0.635 0.2286) (xy -0.635 -0.254) (xy -0.5334 -0.254) (xy -0.5334 -0.2794)
				(xy 0.5334 -0.2794) (xy 0.5334 -0.254) (xy 0.635 -0.254) (xy 0.635 0.254) (xy 0.5334 0.254) (xy 0.5334 0.2794)
				(xy -0.508 0.2794) (xy -0.5334 0.2794)
			)
			(stroke
				(width 0)
				(type default)
			)
			(fill no)
			(layer "F.CrtYd")
		)
		(pad "1" smd rect
			(at 0.40005 0 90)
			(size 0.4572 0.508)
			(layers "F.Cu" "F.Mask" "F.Paste")
			(net "P12V")
		)
		(pad "2" smd rect
			(at -0.40005 0 90)
			(size 0.4572 0.508)
			(layers "F.Cu" "F.Mask" "F.Paste")
			(net "GND")
		)
	)
	(footprint ""
		(layer "F.Cu")
		(at 25.931622 -99.36988)
		(property "Reference" "R46"
			(at -4.080256 -0.075692 0)
			(unlocked yes)
			(layer "F.SilkS")
			(effects
				(font
					(size 0.7874 0.5842)
					(thickness 0.1524)
				)
				(justify left)
			)
		)
		(property "Value" ""
			(at 0 0 0)
			(layer "F.Fab")
			(effects
				(font
					(size 1.27 1.27)
				)
			)
		)
		(duplicate_pad_numbers_are_jumpers no)
		(fp_line
			(start -0.7874 -0.4064)
			(end 0.7874 -0.4064)
			(stroke
				(width 0.1524)
				(type default)
			)
			(layer "F.SilkS")
		)
		(fp_line
			(start -0.7874 0.4064)
			(end -0.7874 -0.4064)
			(stroke
				(width 0.1524)
				(type default)
			)
			(layer "F.SilkS")
		)
		(fp_line
			(start 0.7874 -0.4064)
			(end 0.7874 0.4064)
			(stroke
				(width 0.1524)
				(type default)
			)
			(layer "F.SilkS")
		)
		(fp_line
			(start 0.7874 0.4064)
			(end -0.7874 0.4064)
			(stroke
				(width 0.1524)
				(type default)
			)
			(layer "F.SilkS")
		)
		(fp_poly
			(pts
				(xy -0.508 0.2794) (xy -0.508 0.2286) (xy -0.635 0.2286) (xy -0.635 -0.254) (xy -0.5334 -0.254)
				(xy -0.5334 -0.2794) (xy 0.5334 -0.2794) (xy 0.5334 -0.254) (xy 0.635 -0.254) (xy 0.635 0.254) (xy 0.5334 0.254)
				(xy 0.5334 0.2794)
			)
			(stroke
				(width 0)
				(type default)
			)
			(fill no)
			(layer "F.CrtYd")
		)
		(pad "1" smd rect
			(at 0.40005 0)
			(size 0.4572 0.508)
			(layers "F.Cu" "F.Mask" "F.Paste")
			(net "PSU2_PS_KILL")
		)
		(pad "2" smd rect
			(at -0.40005 0)
			(size 0.4572 0.508)
			(layers "F.Cu" "F.Mask" "F.Paste")
			(net "GND")
		)
	)
	(footprint ""
		(layer "F.Cu")
		(at 46.408086 -239.669066 180)
		(property "Reference" "R89"
			(at 4.341114 0.123698 0)
			(unlocked yes)
			(layer "F.SilkS")
			(effects
				(font
					(size 0.7874 0.5842)
					(thickness 0.1524)
				)
				(justify left)
			)
		)
		(property "Value" ""
			(at 0 0 180)
			(layer "F.Fab")
			(effects
				(font
					(size 1.27 1.27)
				)
			)
		)
		(duplicate_pad_numbers_are_jumpers no)
		(fp_line
			(start 0.7874 0.4064)
			(end -0.7874 0.4064)
			(stroke
				(width 0.1524)
				(type default)
			)
			(layer "F.SilkS")
		)
		(fp_line
			(start 0.7874 -0.4064)
			(end 0.7874 0.4064)
			(stroke
				(width 0.1524)
				(type default)
			)
			(layer "F.SilkS")
		)
		(fp_line
			(start -0.7874 0.4064)
			(end -0.7874 -0.4064)
			(stroke
				(width 0.1524)
				(type default)
			)
			(layer "F.SilkS")
		)
		(fp_line
			(start -0.7874 -0.4064)
			(end 0.7874 -0.4064)
			(stroke
				(width 0.1524)
				(type default)
			)
			(layer "F.SilkS")
		)
		(fp_poly
			(pts
				(xy -0.508 0.2794) (xy -0.508 0.2286) (xy -0.635 0.2286) (xy -0.635 -0.254) (xy -0.5334 -0.254)
				(xy -0.5334 -0.2794) (xy 0.5334 -0.2794) (xy 0.5334 -0.254) (xy 0.635 -0.254) (xy 0.635 0.254) (xy 0.5334 0.254)
				(xy 0.5334 0.2794)
			)
			(stroke
				(width 0)
				(type default)
			)
			(fill no)
			(layer "F.CrtYd")
		)
		(pad "1" smd rect
			(at 0.40005 0 180)
			(size 0.4572 0.508)
			(layers "F.Cu" "F.Mask" "F.Paste")
			(net "PSU1_REMOTE_R_N")
		)
		(pad "2" smd rect
			(at -0.40005 0 180)
			(size 0.4572 0.508)
			(layers "F.Cu" "F.Mask" "F.Paste")
			(net "GND")
		)
	)
	(footprint ""
		(layer "F.Cu")
		(at 2.832862 -415.00044 -90)
		(property "Reference" "R151"
			(at -1.48717 0.13208 90)
			(unlocked yes)
			(layer "F.SilkS")
			(effects
				(font
					(size 0.7874 0.5842)
					(thickness 0.1524)
				)
				(justify left)
			)
		)
		(property "Value" ""
			(at 0 0 270)
			(layer "F.Fab")
			(effects
				(font
					(size 1.27 1.27)
				)
			)
		)
		(duplicate_pad_numbers_are_jumpers no)
		(fp_line
			(start -0.7874 0.4064)
			(end -0.7874 -0.4064)
			(stroke
				(width 0.1524)
				(type default)
			)
			(layer "F.SilkS")
		)
		(fp_line
			(start 0.7874 0.4064)
			(end -0.7874 0.4064)
			(stroke
				(width 0.1524)
				(type default)
			)
			(layer "F.SilkS")
		)
		(fp_line
			(start -0.7874 -0.4064)
			(end 0.7874 -0.4064)
			(stroke
				(width 0.1524)
				(type default)
			)
			(layer "F.SilkS")
		)
		(fp_line
			(start 0.7874 -0.4064)
			(end 0.7874 0.4064)
			(stroke
				(width 0.1524)
				(type default)
			)
			(layer "F.SilkS")
		)
		(fp_poly
			(pts
				(xy -0.508 0.2794) (xy -0.508 0.2286) (xy -0.635 0.2286) (xy -0.635 -0.254) (xy -0.5334 -0.254)
				(xy -0.5334 -0.2794) (xy 0.5334 -0.2794) (xy 0.5334 -0.254) (xy 0.635 -0.254) (xy 0.635 0.254) (xy 0.5334 0.254)
				(xy 0.5334 0.2794)
			)
			(stroke
				(width 0)
				(type default)
			)
			(fill no)
			(layer "F.CrtYd")
		)
		(pad "1" smd rect
			(at 0.40005 0 270)
			(size 0.4572 0.508)
			(layers "F.Cu" "F.Mask" "F.Paste")
			(net "N42132545")
		)
		(pad "2" smd rect
			(at -0.40005 0 270)
			(size 0.4572 0.508)
			(layers "F.Cu" "F.Mask" "F.Paste")
			(net "GND")
		)
	)
	(footprint ""
		(layer "F.Cu")
		(at 26.226008 -450.980556)
		(property "Reference" "R82"
			(at -3.522472 -0.815594 0)
			(unlocked yes)
			(layer "F.SilkS")
			(effects
				(font
					(size 0.7874 0.5842)
					(thickness 0.1524)
				)
				(justify left)
			)
		)
		(property "Value" ""
			(at 0 0 0)
			(layer "F.Fab")
			(effects
				(font
					(size 1.27 1.27)
				)
			)
		)
		(duplicate_pad_numbers_are_jumpers no)
		(fp_line
			(start -0.7874 -0.4064)
			(end 0.7874 -0.4064)
			(stroke
				(width 0.1524)
				(type default)
			)
			(layer "F.SilkS")
		)
		(fp_line
			(start -0.7874 0.4064)
			(end -0.7874 -0.4064)
			(stroke
				(width 0.1524)
				(type default)
			)
			(layer "F.SilkS")
		)
		(fp_line
			(start 0.7874 -0.4064)
			(end 0.7874 0.4064)
			(stroke
				(width 0.1524)
				(type default)
			)
			(layer "F.SilkS")
		)
		(fp_line
			(start 0.7874 0.4064)
			(end -0.7874 0.4064)
			(stroke
				(width 0.1524)
				(type default)
			)
			(layer "F.SilkS")
		)
		(fp_poly
			(pts
				(xy -0.508 0.2794) (xy -0.508 0.2286) (xy -0.635 0.2286) (xy -0.635 -0.254) (xy -0.5334 -0.254)
				(xy -0.5334 -0.2794) (xy 0.5334 -0.2794) (xy 0.5334 -0.254) (xy 0.635 -0.254) (xy 0.635 0.254) (xy 0.5334 0.254)
				(xy 0.5334 0.2794)
			)
			(stroke
				(width 0)
				(type default)
			)
			(fill no)
			(layer "F.CrtYd")
		)
		(pad "1" smd rect
			(at 0.40005 0)
			(size 0.4572 0.508)
			(layers "F.Cu" "F.Mask" "F.Paste")
			(net "PSU6_PS_KILL")
		)
		(pad "2" smd rect
			(at -0.40005 0)
			(size 0.4572 0.508)
			(layers "F.Cu" "F.Mask" "F.Paste")
			(net "P12V_STBY")
		)
	)
	(footprint ""
		(layer "F.Cu")
		(at 69.726556 -172.135546 90)
		(property "Reference" "C34"
			(at -4.082034 0.14097 90)
			(unlocked yes)
			(layer "F.SilkS")
			(effects
				(font
					(size 0.7874 0.5842)
					(thickness 0.1524)
				)
				(justify left)
			)
		)
		(property "Value" ""
			(at 0 0 90)
			(layer "F.Fab")
			(effects
				(font
					(size 1.27 1.27)
				)
			)
		)
		(duplicate_pad_numbers_are_jumpers no)
		(fp_line
			(start 0.7874 -0.4064)
			(end 0.7874 0.4064)
			(stroke
				(width 0.1524)
				(type default)
			)
			(layer "F.SilkS")
		)
		(fp_line
			(start -0.7874 -0.4064)
			(end 0.7874 -0.4064)
			(stroke
				(width 0.1524)
				(type default)
			)
			(layer "F.SilkS")
		)
		(fp_line
			(start 0 0.381)
			(end 0 -0.381)
			(stroke
				(width 0.1524)
				(type default)
			)
			(layer "F.SilkS")
		)
		(fp_line
			(start 0.7874 0.4064)
			(end -0.7874 0.4064)
			(stroke
				(width 0.1524)
				(type default)
			)
			(layer "F.SilkS")
		)
		(fp_line
			(start -0.7874 0.4064)
			(end -0.7874 -0.4064)
			(stroke
				(width 0.1524)
				(type default)
			)
			(layer "F.SilkS")
		)
		(fp_poly
			(pts
				(xy -0.5334 0.254) (xy -0.635 0.254) (xy -0.635 0.2286) (xy -0.635 -0.254) (xy -0.5334 -0.254) (xy -0.5334 -0.2794)
				(xy 0.5334 -0.2794) (xy 0.5334 -0.254) (xy 0.635 -0.254) (xy 0.635 0.254) (xy 0.5334 0.254) (xy 0.5334 0.2794)
				(xy -0.508 0.2794) (xy -0.5334 0.2794)
			)
			(stroke
				(width 0)
				(type default)
			)
			(fill no)
			(layer "F.CrtYd")
		)
		(pad "1" smd rect
			(at 0.40005 0 90)
			(size 0.4572 0.508)
			(layers "F.Cu" "F.Mask" "F.Paste")
			(net "P12V")
		)
		(pad "2" smd rect
			(at -0.40005 0 90)
			(size 0.4572 0.508)
			(layers "F.Cu" "F.Mask" "F.Paste")
			(net "GND")
		)
	)
	(footprint ""
		(layer "F.Cu")
		(at 25.931622 -96.872044)
		(property "Reference" "R68"
			(at -4.080256 -0.075692 0)
			(unlocked yes)
			(layer "F.SilkS")
			(effects
				(font
					(size 0.7874 0.5842)
					(thickness 0.1524)
				)
				(justify left)
			)
		)
		(property "Value" ""
			(at 0 0 0)
			(layer "F.Fab")
			(effects
				(font
					(size 1.27 1.27)
				)
			)
		)
		(duplicate_pad_numbers_are_jumpers no)
		(fp_line
			(start -0.7874 -0.4064)
			(end 0.7874 -0.4064)
			(stroke
				(width 0.1524)
				(type default)
			)
			(layer "F.SilkS")
		)
		(fp_line
			(start -0.7874 0.4064)
			(end -0.7874 -0.4064)
			(stroke
				(width 0.1524)
				(type default)
			)
			(layer "F.SilkS")
		)
		(fp_line
			(start 0.7874 -0.4064)
			(end 0.7874 0.4064)
			(stroke
				(width 0.1524)
				(type default)
			)
			(layer "F.SilkS")
		)
		(fp_line
			(start 0.7874 0.4064)
			(end -0.7874 0.4064)
			(stroke
				(width 0.1524)
				(type default)
			)
			(layer "F.SilkS")
		)
		(fp_poly
			(pts
				(xy -0.508 0.2794) (xy -0.508 0.2286) (xy -0.635 0.2286) (xy -0.635 -0.254) (xy -0.5334 -0.254)
				(xy -0.5334 -0.2794) (xy 0.5334 -0.2794) (xy 0.5334 -0.254) (xy 0.635 -0.254) (xy 0.635 0.254) (xy 0.5334 0.254)
				(xy 0.5334 0.2794)
			)
			(stroke
				(width 0)
				(type default)
			)
			(fill no)
			(layer "F.CrtYd")
		)
		(pad "1" smd rect
			(at 0.40005 0)
			(size 0.4572 0.508)
			(layers "F.Cu" "F.Mask" "F.Paste")
			(net "PSU2_RESET")
		)
		(pad "2" smd rect
			(at -0.40005 0)
			(size 0.4572 0.508)
			(layers "F.Cu" "F.Mask" "F.Paste")
			(net "P12V_STBY")
		)
	)
)
